%FSTAX23Y23*%
%MOIN*%
%SFA1B1*%

%IPPOS*%
%ADD26O,0.078740X0.023620*%
%ADD27R,0.039370X0.074800*%
%ADD28R,0.070870X0.074800*%
%ADD29R,0.055910X0.061020*%
%ADD30R,0.017720X0.054330*%
%ADD31R,0.064960X0.051180*%
%ADD32R,0.078740X0.098430*%
%ADD33R,0.019680X0.090550*%
%ADD34R,0.041340X0.039370*%
%ADD35R,0.086610X0.041340*%
%ADD36R,0.019680X0.035430*%
%ADD37O,0.057090X0.017720*%
%ADD38R,0.077560X0.022440*%
%ADD39R,0.025590X0.041340*%
%ADD40R,0.051180X0.074800*%
%ADD41R,0.039370X0.070870*%
%ADD42R,0.039370X0.090550*%
%ADD43R,0.041340X0.045280*%
%ADD44R,0.027560X0.045280*%
%ADD45R,0.053150X0.027560*%
%ADD46R,0.050000X0.200000*%
%ADD47R,0.057090X0.037400*%
%ADD48R,0.028350X0.039370*%
%ADD49R,0.025590X0.023620*%
%ADD50R,0.028000X0.165000*%
%ADD51R,0.028000X0.126000*%
%ADD52R,0.031500X0.066930*%
%ADD53R,0.070870X0.009840*%
%ADD54R,0.026570X0.009840*%
%ADD55R,0.009840X0.022640*%
%ADD56R,0.027560X0.035430*%
%ADD57R,0.038580X0.034250*%
%ADD58R,0.212600X0.114170*%
%ADD59R,0.165350X0.125980*%
%ADD60R,0.096460X0.124020*%
%ADD61R,0.033470X0.039370*%
%ADD62R,0.057090X0.045280*%
%ADD63R,0.037400X0.039370*%
%ADD64R,0.025200X0.026770*%
%ADD65R,0.010830X0.009840*%
%ADD66R,0.009840X0.010830*%
%ADD67R,0.061020X0.009840*%
%ADD68R,0.066930X0.053150*%
%ADD69R,0.009840X0.061020*%
%ADD70R,0.053150X0.066930*%
%ADD71R,0.045280X0.057090*%
%ADD72R,0.026770X0.025200*%
%ADD73R,0.039370X0.037400*%
%ADD74R,0.039370X0.033470*%
%ADD75R,0.039370X0.028350*%
%ADD76R,0.023620X0.025590*%
%ADD77R,0.082870X0.044090*%
%ADD78R,0.035430X0.027560*%
%LNgrandmaster-1*%
%LPD*%
G54D26*
X02756Y03287D03*
Y03237D03*
Y03187D03*
Y03137D03*
Y03087D03*
Y03037D03*
Y02987D03*
Y02937D03*
X03111Y03287D03*
Y03237D03*
Y03187D03*
Y03137D03*
Y03087D03*
Y03037D03*
Y02987D03*
Y02937D03*
G54D27*
X02271Y04275D03*
G54D28*
X02377Y04275D03*
G54D29*
X02234Y04173D03*
X0243D03*
G54D30*
X02383Y0417D03*
X02358D03*
X02332D03*
X02306D03*
X02281D03*
G54D31*
X02465Y04275D03*
X02199D03*
G54D32*
X04046Y04244D03*
Y04027D03*
X03696D03*
Y04244D03*
G54D33*
X03934Y04023D03*
X03902D03*
X03871D03*
X03839D03*
X03808D03*
G54D34*
X00594Y00906D03*
Y01956D03*
Y02481D03*
Y01431D03*
G54D35*
X00654Y00964D03*
Y00847D03*
Y01897D03*
Y02014D03*
Y02422D03*
Y02539D03*
Y01489D03*
Y01372D03*
G54D36*
X03469Y03661D03*
X03444Y0375D03*
X03495D03*
X02834Y03661D03*
X02809Y0375D03*
X0286D03*
X02719Y03661D03*
X02694Y0375D03*
X02745D03*
X03244Y03661D03*
X03219Y0375D03*
X0327D03*
G54D37*
X01846Y04024D03*
Y04049D03*
Y04074D03*
Y04099D03*
Y04124D03*
Y04149D03*
Y04174D03*
Y04199D03*
X01631Y04024D03*
Y04049D03*
Y04074D03*
Y04099D03*
Y04124D03*
Y04149D03*
Y04174D03*
Y04199D03*
X03987Y03683D03*
Y03708D03*
Y03733D03*
Y03758D03*
Y03783D03*
Y03808D03*
Y03833D03*
Y03858D03*
X03772Y03683D03*
Y03708D03*
Y03733D03*
Y03758D03*
Y03783D03*
Y03808D03*
Y03833D03*
Y03858D03*
G54D38*
X06352Y02241D03*
Y02291D03*
Y02341D03*
Y02391D03*
X06157D03*
Y02341D03*
Y02291D03*
Y02241D03*
X06637Y02031D03*
Y01981D03*
Y01931D03*
Y01881D03*
X06832D03*
Y01931D03*
Y01981D03*
Y02031D03*
G54D39*
X06341Y03701D03*
X06197D03*
X06031D03*
X05887D03*
X06202Y03566D03*
X06346D03*
G54D40*
X06726Y03168D03*
X06943D03*
Y03294D03*
X06726D03*
G54D41*
X03451Y03206D03*
X03392D03*
X03451Y03395D03*
X0351D03*
X03569Y03206D03*
X03333Y03395D03*
Y03206D03*
X0351D03*
X03392Y03395D03*
G54D42*
X03569Y03385D03*
G54D43*
X03438Y03051D03*
Y02892D03*
X03531Y03051D03*
Y02892D03*
G54D44*
X03484Y02892D03*
Y03051D03*
G54D45*
X03444Y02995D03*
Y02948D03*
X03525D03*
Y02995D03*
G54D46*
X03344Y04221D03*
Y03951D03*
X03244Y04221D03*
Y03951D03*
X03144Y04221D03*
Y03951D03*
X03044Y04221D03*
Y03951D03*
X02944Y04221D03*
Y03951D03*
G54D47*
X03349Y03666D03*
Y03745D03*
X02944Y03666D03*
Y03745D03*
X03044Y03666D03*
Y03745D03*
X03144Y03666D03*
Y03745D03*
G54D48*
X03477Y02797D03*
X03532D03*
X06035Y03556D03*
X0609D03*
X0415Y03603D03*
X04204D03*
X06897Y01816D03*
X06842D03*
X06782D03*
X06727D03*
X06367Y02451D03*
X06312D03*
X04167Y03701D03*
X04112D03*
X04652Y04206D03*
X04707D03*
X05212D03*
X05267D03*
X04652Y04121D03*
X04707D03*
X05267Y04126D03*
X05212D03*
G54D49*
X03701Y03786D03*
X03668D03*
X03701Y03861D03*
X03668D03*
G54D50*
X02545Y00137D03*
X02466D03*
X02348D03*
X0282D03*
X01915D03*
X02033D03*
X02663D03*
X02702D03*
X0286D03*
X02978D03*
X0219D03*
X01994D03*
X01954D03*
X03017D03*
X02309D03*
X02112D03*
X02151D03*
X02387D03*
X02427D03*
X02584D03*
X02624D03*
X02742D03*
X02781D03*
X02899D03*
X02938D03*
X02505D03*
X02072D03*
X01797D03*
X01836D03*
X01875D03*
X03096D03*
G54D51*
X03057Y00157D03*
G54D52*
X04957Y04206D03*
X05091D03*
X04432D03*
X04566D03*
G54D53*
X04068Y01599D03*
X03911D03*
Y01619D03*
X04068D03*
X03911Y01639D03*
X04068D03*
X03911Y01659D03*
X04068D03*
X03911Y01679D03*
X04068D03*
X03911Y01699D03*
X04068D03*
X03911Y01719D03*
X04068D03*
X03911Y01739D03*
X04068D03*
X03911Y01759D03*
X04068D03*
X03911Y01779D03*
X04068D03*
G54D54*
X06511Y03191D03*
Y03172D03*
Y03211D03*
Y03231D03*
Y0325D03*
Y0327D03*
Y0329D03*
Y03309D03*
Y03329D03*
X06388D03*
Y03309D03*
Y0329D03*
Y0327D03*
Y0325D03*
Y03231D03*
Y03211D03*
Y03191D03*
Y03172D03*
Y03152D03*
X06511D03*
G54D55*
X06479Y03332D03*
X06459D03*
X0644D03*
X0642D03*
Y0315D03*
X0644D03*
X06459D03*
X06479D03*
G54D56*
X00901Y00718D03*
X0096D03*
X00908Y02284D03*
X00967D03*
X009Y01747D03*
X00959D03*
X00904Y01224D03*
X00963D03*
G54D57*
X04149Y02789D03*
Y02842D03*
X04434Y02789D03*
Y02842D03*
G54D58*
X06679Y0242D03*
Y02802D03*
X06319Y01842D03*
Y0146D03*
G54D59*
X04909Y03961D03*
Y02808D03*
G54D60*
X01157Y00906D03*
X00932D03*
Y01956D03*
X01157D03*
X00932Y02481D03*
X01157D03*
Y01431D03*
X00932D03*
G54D61*
X01249Y04254D03*
Y04197D03*
X03589Y03852D03*
Y03909D03*
Y03784D03*
Y03727D03*
X00644Y04197D03*
Y04254D03*
X00846Y04197D03*
Y04254D03*
X01048D03*
Y04197D03*
G54D62*
X04339Y0278D03*
Y02851D03*
X06334Y0211D03*
Y02181D03*
X06659Y02166D03*
Y02095D03*
X06253Y02826D03*
Y02755D03*
X06372Y02826D03*
Y02755D03*
X04104Y0377D03*
Y03841D03*
X02209Y03716D03*
Y03645D03*
X02639Y03535D03*
Y03606D03*
X03693Y03188D03*
Y03117D03*
X04064Y0278D03*
Y02851D03*
X03959Y0278D03*
Y02851D03*
X04234Y0278D03*
Y02851D03*
G54D63*
X04039Y03029D03*
Y03092D03*
X06469Y02239D03*
Y02302D03*
X06519Y01954D03*
Y02017D03*
X04194Y03774D03*
Y03837D03*
X03688Y03266D03*
Y03329D03*
X06604Y03264D03*
Y03327D03*
Y03192D03*
Y03129D03*
G54D64*
X04109Y03044D03*
Y03077D03*
X06939Y01889D03*
Y01922D03*
X06064Y02344D03*
Y02377D03*
X06584Y03039D03*
Y03072D03*
X02139Y03697D03*
Y03664D03*
X02724Y03559D03*
Y03592D03*
X03769Y03234D03*
Y03201D03*
X04454Y03044D03*
Y03077D03*
X04394Y03044D03*
Y03077D03*
X04334Y03044D03*
Y03077D03*
X04274Y03044D03*
Y03077D03*
X04219Y03044D03*
Y03077D03*
X04164Y03044D03*
Y03077D03*
G54D65*
X03269Y02834D03*
Y02814D03*
Y02795D03*
X03209D03*
Y02814D03*
Y02834D03*
G54D66*
X03249Y02784D03*
X03229D03*
Y02845D03*
X03249D03*
G54D67*
X03492Y01398D03*
Y01378D03*
Y01457D03*
Y01477D03*
Y01772D03*
Y01496D03*
Y01792D03*
Y0189D03*
Y01851D03*
Y0187D03*
Y01831D03*
X03651Y0187D03*
Y0189D03*
Y01929D03*
X03492Y01339D03*
Y01359D03*
X03651Y01792D03*
Y01772D03*
Y01851D03*
Y01831D03*
Y01949D03*
Y01988D03*
Y01969D03*
X03492Y01988D03*
Y01969D03*
X03651Y01693D03*
X03492Y01634D03*
Y01673D03*
Y01654D03*
Y01693D03*
X03651Y01733D03*
Y01752D03*
Y01654D03*
Y01575D03*
Y01555D03*
Y01673D03*
Y01634D03*
X03492Y01929D03*
Y01555D03*
Y02008D03*
Y0191D03*
Y01811D03*
Y01713D03*
Y01614D03*
Y01516D03*
Y01418D03*
X03651Y02008D03*
Y0191D03*
Y01811D03*
Y01713D03*
Y01614D03*
Y01516D03*
Y01418D03*
X03492Y01949D03*
X03651Y01595D03*
X03492Y01536D03*
X03651Y01496D03*
Y01477D03*
Y01457D03*
Y01437D03*
Y01398D03*
Y01378D03*
Y01359D03*
Y01339D03*
X03492Y01319D03*
X03651D03*
X03492Y01733D03*
Y01752D03*
X03651Y01536D03*
X03492Y01575D03*
Y01595D03*
Y01437D03*
Y02087D03*
Y02067D03*
Y02047D03*
Y02028D03*
X03651Y02087D03*
Y02067D03*
Y02047D03*
Y02028D03*
X01776Y01634D03*
Y01614D03*
Y0187D03*
Y02028D03*
Y0191D03*
Y01831D03*
Y01949D03*
Y01733D03*
Y01772D03*
X01617Y01929D03*
Y01851D03*
Y0191D03*
Y02028D03*
X01776Y02008D03*
Y01969D03*
Y01457D03*
Y01674D03*
X01617Y0187D03*
Y01969D03*
X01776Y01929D03*
Y01851D03*
Y01811D03*
Y01654D03*
X01617Y02008D03*
X01776Y01752D03*
Y01713D03*
X01617Y01949D03*
X01776Y01555D03*
Y01575D03*
X01617Y01516D03*
Y01457D03*
Y01811D03*
Y01831D03*
X01776Y01437D03*
X01617Y01359D03*
X01776Y01339D03*
X01617Y01575D03*
Y01437D03*
Y01536D03*
Y01555D03*
Y01614D03*
Y01733D03*
Y01674D03*
Y01378D03*
Y01477D03*
Y01418D03*
Y01752D03*
X01776Y01359D03*
X01617Y01339D03*
Y01634D03*
Y01772D03*
X01776Y01378D03*
Y01319D03*
Y01418D03*
X01617Y01319D03*
X01776Y01477D03*
X01617Y01713D03*
Y01654D03*
X01776Y01516D03*
X01617Y02048D03*
X01776D03*
Y01398D03*
Y01496D03*
Y01595D03*
Y01693D03*
Y01792D03*
Y0189D03*
Y01988D03*
X01617Y01398D03*
Y01496D03*
Y01595D03*
Y01693D03*
Y01792D03*
Y0189D03*
Y01988D03*
Y02087D03*
X01776D03*
Y02067D03*
Y01536D03*
X01617Y02067D03*
G54D68*
X03571Y02131D03*
Y01275D03*
X01696Y01275D03*
Y02131D03*
G54D69*
X0298Y02518D03*
Y02358D03*
X02882Y02518D03*
X02783D03*
X02685D03*
X02586D03*
X02488D03*
X0239D03*
X02291D03*
X02882Y02358D03*
X02783D03*
X02685D03*
X02586D03*
X02488D03*
X0239D03*
X02291D03*
X02941D03*
X02961D03*
X02901D03*
X02921D03*
X02842D03*
X02862D03*
X02803D03*
X02823D03*
X02744D03*
X02764D03*
X02705D03*
X02724D03*
X02646D03*
X02665D03*
X02606D03*
X02626D03*
X02547D03*
X02567D03*
X02508D03*
X02527D03*
X02449D03*
X02468D03*
X02409D03*
X02429D03*
X0235D03*
X0237D03*
X02212Y02518D03*
X02232D03*
Y02358D03*
X02212D03*
X02252Y02518D03*
X02272D03*
X02409D03*
X02429D03*
X0235D03*
X0237D03*
X02508D03*
X02527D03*
X02449D03*
X02468D03*
X02606D03*
X02547D03*
X02626D03*
X02567D03*
X02705D03*
X02724D03*
X02646D03*
X02665D03*
X02803D03*
X02823D03*
X02744D03*
X02764D03*
X02901D03*
X02921D03*
X02842D03*
X02862D03*
X02941D03*
X02961D03*
X02252Y02358D03*
X02311D03*
X02331D03*
X02272D03*
X02311Y02518D03*
X02331D03*
X02803Y01038D03*
X02823D03*
X02862Y00878D03*
X02882D03*
X02744D03*
X02764D03*
X02685Y01038D03*
X02705D03*
X02587Y00878D03*
Y01038D03*
X02646Y00878D03*
X02626D03*
X02744Y01038D03*
X02764D03*
X02803Y00878D03*
X02823D03*
X02685D03*
X02705D03*
X02626Y01038D03*
X02646D03*
X02232Y00878D03*
X02429D03*
X0237D03*
X0235D03*
X02331D03*
X02291D03*
X0239D03*
X02488D03*
X02527D03*
X02547D03*
X02567D03*
X02449D03*
X02468D03*
X02252D03*
X02272D03*
X02567Y01038D03*
X0237D03*
X0239D03*
X02429D03*
X02468D03*
X02488D03*
X02449D03*
X02291D03*
X02272D03*
X02252D03*
X02232D03*
X0235D03*
X02331D03*
X02547D03*
X02527D03*
X02862D03*
X02882D03*
X02921Y00878D03*
Y01038D03*
X02941Y00878D03*
Y01038D03*
X0298Y00878D03*
Y01038D03*
X02961D03*
Y00878D03*
X02901Y01038D03*
X02842D03*
X02783D03*
X02724D03*
X02665D03*
X02606D03*
X02508D03*
X02409D03*
X02311D03*
X02901Y00878D03*
X02842D03*
X02783D03*
X02724D03*
X02665D03*
X02606D03*
X02508D03*
X02409D03*
X02311D03*
X02212D03*
Y01038D03*
G54D70*
X02168Y02438D03*
X02168Y00958D03*
X03024D03*
X03024Y02438D03*
G54D71*
X05741Y03361D03*
X05812D03*
X06629Y01421D03*
X067D03*
X06629Y01531D03*
X067D03*
X06439Y03071D03*
X0651D03*
X0373Y00726D03*
X03659D03*
X01802Y04276D03*
X01873D03*
X0428Y03246D03*
X04209D03*
G54D72*
X05634Y03359D03*
X05668D03*
X06327Y02656D03*
X06361D03*
X06327Y02501D03*
X06361D03*
X06327Y02556D03*
X06361D03*
X06327Y02611D03*
X06361D03*
X06676Y01611D03*
X06642D03*
X06676Y01671D03*
X06642D03*
X06676Y01721D03*
X06642D03*
X06676Y01776D03*
X06642D03*
X03716Y00636D03*
X03682D03*
G54D73*
X06906Y02096D03*
X06843D03*
X06093Y02171D03*
X06156D03*
X01664Y04273D03*
X01727D03*
G54D74*
X04275Y03603D03*
X04332D03*
G54D75*
X06749Y02143D03*
Y02088D03*
X06234Y02183D03*
Y02128D03*
X07009Y01883D03*
Y01938D03*
X06004Y02393D03*
Y02338D03*
X02146Y02624D03*
Y02679D03*
X00638Y04038D03*
Y04093D03*
X0084D03*
Y04038D03*
X01042Y04093D03*
Y04038D03*
X01243Y04093D03*
Y04038D03*
X06122Y02488D03*
Y02433D03*
X01933Y04074D03*
Y04129D03*
G54D76*
X02503Y00607D03*
Y00573D03*
X03055Y00607D03*
Y00573D03*
G54D77*
X02334Y03404D03*
Y03483D03*
Y03562D03*
Y0364D03*
X02509Y03404D03*
Y03562D03*
Y03483D03*
Y0364D03*
G54D78*
X01346Y04082D03*
Y04141D03*
Y04037D03*
Y03978D03*
X02151Y04015D03*
Y04074D03*
X02212Y04015D03*
Y04074D03*
X02387Y02899D03*
Y02958D03*
M02*